(kicad_pcb
	(version 20260206)
	(generator "pcbnew")
	(generator_version "10.0")
	(general
		(thickness 1.6)
		(legacy_teardrops no)
	)
	(paper "A4")
	(title_block
		(title "01162023_DA0F0TEBIF0_F0T_Expander_BD_F_brd_V02_OCP.brd")
		(comment 1 "Grand Teton / footprints 7919-7925 of 9728")
	)
	(layers
		(0 "F.Cu" signal "TOP")
		(4 "In1.Cu" signal "GND")
		(6 "In2.Cu" signal "VCC")
		(8 "In3.Cu" signal "VCC1")
		(10 "In4.Cu" signal "GND1")
		(12 "In5.Cu" signal "IN1")
		(14 "In6.Cu" signal "GND2")
		(16 "In7.Cu" signal "IN2")
		(18 "In8.Cu" signal "GND3")
		(20 "In9.Cu" signal "IN3")
		(22 "In10.Cu" signal "GND4")
		(24 "In11.Cu" signal "IN4")
		(26 "In12.Cu" signal "GND5")
		(28 "In13.Cu" signal "IN5")
		(30 "In14.Cu" signal "GND6")
		(32 "In15.Cu" signal "IN6")
		(34 "In16.Cu" signal "GND7")
		(2 "B.Cu" signal "BOTTOM")
		(9 "F.Adhes" user "F.Adhesive")
		(11 "B.Adhes" user "B.Adhesive")
		(13 "F.Paste" user "Package Geometry/Pastemask Top")
		(15 "B.Paste" user "Package Geometry/Pastemask Bottom")
		(5 "F.SilkS" user "Ref Des/Silkscreen Top")
		(7 "B.SilkS" user "Ref Des/Silkscreen Bottom")
		(1 "F.Mask" user "Board Geometry/Soldermask Top")
		(3 "B.Mask" user "Board Geometry/Soldermask Bottom")
		(17 "Dwgs.User" user "User.Drawings")
		(19 "Cmts.User" user "User.Comments")
		(21 "Eco1.User" user "User.Eco1")
		(23 "Eco2.User" user "User.Eco2")
		(25 "Edge.Cuts" user "Board Geometry/Outline")
		(27 "Margin" user)
		(31 "F.CrtYd" user "Package Geometry/Place Bound Top")
		(29 "B.CrtYd" user "Package Geometry/Place Bound Bottom")
		(35 "F.Fab" user "Ref Des/Assembly Top")
		(33 "B.Fab" user "Ref Des/Assembly Bottom")
	)
	(footprint ""
		(layer "B.Cu")
		(at 242.110768 8.076692)
		(property "Reference" "DE12T_2"
			(at 2.694432 3.303778 0)
			(unlocked yes)
			(layer "B.SilkS")
			(effects
				(font
					(size 0.7874 0.5842)
					(thickness 0.1524)
				)
				(justify left mirror)
			)
		)
		(property "Value" ""
			(at 0 0 0)
			(layer "B.Fab")
			(effects
				(font
					(size 1.27 1.27)
				)
				(justify mirror)
			)
		)
		(duplicate_pad_numbers_are_jumpers no)
		(fp_line
			(start -1.2192 -2.1082)
			(end -1.2192 2.1082)
			(stroke
				(width 0.1524)
				(type default)
			)
			(layer "B.SilkS")
		)
		(fp_line
			(start -1.2192 2.1082)
			(end 1.2192 2.1082)
			(stroke
				(width 0.1524)
				(type default)
			)
			(layer "B.SilkS")
		)
		(fp_line
			(start 1.2192 -2.1082)
			(end -1.2192 -2.1082)
			(stroke
				(width 0.1524)
				(type default)
			)
			(layer "B.SilkS")
		)
		(fp_line
			(start 1.2192 2.1082)
			(end 1.2192 -2.1082)
			(stroke
				(width 0.1524)
				(type default)
			)
			(layer "B.SilkS")
		)
		(pad "" np_thru_hole circle
			(at -3.4671 -1.27 270)
			(size 1.0414 1.0414)
			(drill 1.0414)
			(layers "*.Cu" "*.Mask")
			(clearance 0.381)
			(thermal_gap 0.381)
		)
		(pad "" np_thru_hole circle
			(at -3.4671 1.27 270)
			(size 1.0414 1.0414)
			(drill 1.0414)
			(layers "*.Cu" "*.Mask")
			(clearance 0.381)
			(thermal_gap 0.381)
		)
		(pad "" np_thru_hole circle
			(at 2.8829 -1.27 270)
			(size 1.0414 1.0414)
			(drill 1.0414)
			(layers "*.Cu" "*.Mask")
			(clearance 0.381)
			(thermal_gap 0.381)
		)
		(pad "" np_thru_hole circle
			(at 2.8829 1.27 270)
			(size 1.0414 1.0414)
			(drill 1.0414)
			(layers "*.Cu" "*.Mask")
			(clearance 0.381)
			(thermal_gap 0.381)
		)
		(pad "1" smd rect
			(at -0.8255 -0.249936 270)
			(size 0.3048 0.508)
			(layers "B.Cu" "B.Mask" "B.Paste")
			(net "85_10INCH_BOTTOM_DN")
		)
		(pad "2" smd rect
			(at -0.8255 0.249936 270)
			(size 0.3048 0.508)
			(layers "B.Cu" "B.Mask" "B.Paste")
			(net "85_10INCH_BOTTOM_DP")
		)
		(pad "3" smd circle
			(at 0 0 180)
			(size 0 0)
			(layers "B.Cu" "B.Mask" "B.Paste")
			(net "COUPON_GND2")
		)
		(zone
			(layers "F.Cu" "B.Cu" "In1.Cu" "In2.Cu" "In3.Cu" "In4.Cu" "In5.Cu" "In6.Cu"
				"In7.Cu" "In8.Cu" "In9.Cu" "In10.Cu" "In11.Cu" "In12.Cu" "In13.Cu" "In14.Cu"
				"In15.Cu" "In16.Cu"
			)
			(hatch none 0.5)
			(connect_pads
				(clearance 0)
			)
			(min_thickness 0.25)
			(keepout
				(tracks not_allowed)
				(vias allowed)
				(pads allowed)
				(copperpour not_allowed)
				(footprints allowed)
			)
			(placement
				(enabled no)
				(sheetname "")
			)
			(fill
				(thermal_gap 0.5)
				(thermal_bridge_width 0.5)
				(island_removal_mode 0)
			)
			(polygon
				(pts
					(arc
						(start 239.570768 6.806692)
						(mid 237.716568 6.806692)
						(end 239.570768 6.806692)
					)
				)
			)
		)
		(zone
			(layers "F.Cu" "B.Cu" "In1.Cu" "In2.Cu" "In3.Cu" "In4.Cu" "In5.Cu" "In6.Cu"
				"In7.Cu" "In8.Cu" "In9.Cu" "In10.Cu" "In11.Cu" "In12.Cu" "In13.Cu" "In14.Cu"
				"In15.Cu" "In16.Cu"
			)
			(hatch none 0.5)
			(connect_pads
				(clearance 0)
			)
			(min_thickness 0.25)
			(keepout
				(tracks not_allowed)
				(vias allowed)
				(pads allowed)
				(copperpour not_allowed)
				(footprints allowed)
			)
			(placement
				(enabled no)
				(sheetname "")
			)
			(fill
				(thermal_gap 0.5)
				(thermal_bridge_width 0.5)
				(island_removal_mode 0)
			)
			(polygon
				(pts
					(arc
						(start 239.570768 9.346692)
						(mid 237.716568 9.346692)
						(end 239.570768 9.346692)
					)
				)
			)
		)
		(zone
			(layers "F.Cu" "B.Cu" "In1.Cu" "In2.Cu" "In3.Cu" "In4.Cu" "In5.Cu" "In6.Cu"
				"In7.Cu" "In8.Cu" "In9.Cu" "In10.Cu" "In11.Cu" "In12.Cu" "In13.Cu" "In14.Cu"
				"In15.Cu" "In16.Cu"
			)
			(hatch none 0.5)
			(connect_pads
				(clearance 0)
			)
			(min_thickness 0.25)
			(keepout
				(tracks not_allowed)
				(vias allowed)
				(pads allowed)
				(copperpour not_allowed)
				(footprints allowed)
			)
			(placement
				(enabled no)
				(sheetname "")
			)
			(fill
				(thermal_gap 0.5)
				(thermal_bridge_width 0.5)
				(island_removal_mode 0)
			)
			(polygon
				(pts
					(arc
						(start 245.920768 6.806692)
						(mid 244.066568 6.806692)
						(end 245.920768 6.806692)
					)
				)
			)
		)
		(zone
			(layers "F.Cu" "B.Cu" "In1.Cu" "In2.Cu" "In3.Cu" "In4.Cu" "In5.Cu" "In6.Cu"
				"In7.Cu" "In8.Cu" "In9.Cu" "In10.Cu" "In11.Cu" "In12.Cu" "In13.Cu" "In14.Cu"
				"In15.Cu" "In16.Cu"
			)
			(hatch none 0.5)
			(connect_pads
				(clearance 0)
			)
			(min_thickness 0.25)
			(keepout
				(tracks not_allowed)
				(vias allowed)
				(pads allowed)
				(copperpour not_allowed)
				(footprints allowed)
			)
			(placement
				(enabled no)
				(sheetname "")
			)
			(fill
				(thermal_gap 0.5)
				(thermal_bridge_width 0.5)
				(island_removal_mode 0)
			)
			(polygon
				(pts
					(arc
						(start 245.920768 9.346692)
						(mid 244.066568 9.346692)
						(end 245.920768 9.346692)
					)
				)
			)
		)
		(zone
			(layer "B.Cu")
			(hatch none 0.5)
			(connect_pads
				(clearance 0)
			)
			(min_thickness 0.25)
			(keepout
				(tracks not_allowed)
				(vias allowed)
				(pads allowed)
				(copperpour not_allowed)
				(footprints allowed)
			)
			(placement
				(enabled no)
				(sheetname "")
			)
			(fill
				(thermal_gap 0.5)
				(thermal_bridge_width 0.5)
				(island_removal_mode 0)
			)
			(polygon
				(pts
					(xy 240.993168 7.528052) (xy 240.993168 7.623556) (xy 241.590068 7.623556) (xy 241.590068 8.029956)
					(xy 240.993168 8.029956) (xy 240.993168 8.123428) (xy 241.590068 8.123428) (xy 241.590068 8.529828)
					(xy 240.993168 8.529828) (xy 240.993168 8.625332) (xy 241.691668 8.625332) (xy 241.691668 7.528052)
				)
			)
		)
	)
	(footprint ""
		(layer "B.Cu")
		(at 140.559282 -226.535996 -90)
		(property "Reference" "R3468"
			(at 0 0 90)
			(layer "B.SilkS")
			(hide yes)
			(effects
				(font
					(size 1.27 1.27)
				)
				(justify mirror)
			)
		)
		(property "Value" ""
			(at 0 0 90)
			(layer "B.Fab")
			(effects
				(font
					(size 1.27 1.27)
				)
				(justify mirror)
			)
		)
		(duplicate_pad_numbers_are_jumpers no)
		(fp_line
			(start -0.7874 0.4064)
			(end 0.7874 0.4064)
			(stroke
				(width 0.1524)
				(type default)
			)
			(layer "B.SilkS")
		)
		(fp_line
			(start 0.7874 0.4064)
			(end 0.7874 -0.4064)
			(stroke
				(width 0.1524)
				(type default)
			)
			(layer "B.SilkS")
		)
		(fp_line
			(start -0.7874 -0.4064)
			(end -0.7874 0.4064)
			(stroke
				(width 0.1524)
				(type default)
			)
			(layer "B.SilkS")
		)
		(fp_line
			(start 0.7874 -0.4064)
			(end -0.7874 -0.4064)
			(stroke
				(width 0.1524)
				(type default)
			)
			(layer "B.SilkS")
		)
		(fp_line
			(start -0.67945 0.3048)
			(end -0.120396 0.3048)
			(stroke
				(width 0.1)
				(type default)
			)
			(layer "B.Fab")
		)
		(fp_line
			(start -0.120396 0.3048)
			(end -0.120396 0.2794)
			(stroke
				(width 0.1)
				(type default)
			)
			(layer "B.Fab")
		)
		(fp_line
			(start 0.12065 0.3048)
			(end 0.67945 0.3048)
			(stroke
				(width 0.1)
				(type default)
			)
			(layer "B.Fab")
		)
		(fp_line
			(start 0.67945 0.3048)
			(end 0.67945 -0.305054)
			(stroke
				(width 0.1)
				(type default)
			)
			(layer "B.Fab")
		)
		(fp_line
			(start -0.120396 0.2794)
			(end 0.12065 0.2794)
			(stroke
				(width 0.1)
				(type default)
			)
			(layer "B.Fab")
		)
		(fp_line
			(start 0.12065 0.2794)
			(end 0.12065 0.3048)
			(stroke
				(width 0.1)
				(type default)
			)
			(layer "B.Fab")
		)
		(fp_line
			(start -0.12065 -0.2794)
			(end -0.12065 -0.3048)
			(stroke
				(width 0.1)
				(type default)
			)
			(layer "B.Fab")
		)
		(fp_line
			(start 0.12065 -0.2794)
			(end -0.12065 -0.2794)
			(stroke
				(width 0.1)
				(type default)
			)
			(layer "B.Fab")
		)
		(fp_line
			(start -0.67945 -0.3048)
			(end -0.67945 0.3048)
			(stroke
				(width 0.1)
				(type default)
			)
			(layer "B.Fab")
		)
		(fp_line
			(start -0.12065 -0.3048)
			(end -0.67945 -0.3048)
			(stroke
				(width 0.1)
				(type default)
			)
			(layer "B.Fab")
		)
		(fp_line
			(start 0.12065 -0.305054)
			(end 0.12065 -0.2794)
			(stroke
				(width 0.1)
				(type default)
			)
			(layer "B.Fab")
		)
		(fp_line
			(start 0.67945 -0.305054)
			(end 0.12065 -0.305054)
			(stroke
				(width 0.1)
				(type default)
			)
			(layer "B.Fab")
		)
		(pad "1" smd circle
			(at 0.40005 0 90)
			(size 0 0)
			(layers "B.Cu" "B.Mask" "B.Paste")
			(net "P1V8_PEX")
		)
		(pad "2" smd circle
			(at -0.40005 0 90)
			(size 0 0)
			(layers "B.Cu" "B.Mask" "B.Paste")
			(net "SPI_PEX1_CS_MUX_R_N")
		)
	)
	(footprint ""
		(layer "B.Cu")
		(at 169.099992 -290.199826 90)
		(property "Reference" "C1431"
			(at 0 0 90)
			(layer "B.SilkS")
			(hide yes)
			(effects
				(font
					(size 1.27 1.27)
				)
				(justify mirror)
			)
		)
		(property "Value" ""
			(at 0 0 90)
			(layer "B.Fab")
			(effects
				(font
					(size 1.27 1.27)
				)
				(justify mirror)
			)
		)
		(duplicate_pad_numbers_are_jumpers no)
		(fp_line
			(start 0.299974 -0.150114)
			(end -0.299974 -0.150114)
			(stroke
				(width 0.1)
				(type default)
			)
			(layer "B.Fab")
		)
		(fp_line
			(start -0.299974 -0.150114)
			(end -0.299974 0.150114)
			(stroke
				(width 0.1)
				(type default)
			)
			(layer "B.Fab")
		)
		(fp_line
			(start 0.299974 0.150114)
			(end 0.299974 -0.150114)
			(stroke
				(width 0.1)
				(type default)
			)
			(layer "B.Fab")
		)
		(fp_line
			(start -0.299974 0.150114)
			(end 0.299974 0.150114)
			(stroke
				(width 0.1)
				(type default)
			)
			(layer "B.Fab")
		)
		(pad "1" smd rect
			(at 0.2667 0 270)
			(size 0.3048 0.381)
			(layers "B.Cu" "B.Mask" "B.Paste")
			(net "P0V8_SERDES_VDDA_PEX1")
		)
		(pad "2" smd rect
			(at -0.2667 0 270)
			(size 0.3048 0.381)
			(layers "B.Cu" "B.Mask" "B.Paste")
			(net "GND")
		)
	)
	(footprint ""
		(layer "B.Cu")
		(at 345.293442 -220.38691 90)
		(property "Reference" "C2046"
			(at 0 0 90)
			(layer "B.SilkS")
			(hide yes)
			(effects
				(font
					(size 1.27 1.27)
				)
				(justify mirror)
			)
		)
		(property "Value" ""
			(at 0 0 90)
			(layer "B.Fab")
			(effects
				(font
					(size 1.27 1.27)
				)
				(justify mirror)
			)
		)
		(duplicate_pad_numbers_are_jumpers no)
		(fp_line
			(start 0.69215 -0.2921)
			(end -0.69215 -0.2921)
			(stroke
				(width 0.1524)
				(type default)
			)
			(layer "B.SilkS")
		)
		(fp_line
			(start -0.69215 -0.2921)
			(end -0.69215 0.2921)
			(stroke
				(width 0.1524)
				(type default)
			)
			(layer "B.SilkS")
		)
		(fp_line
			(start 0.69215 0.2921)
			(end 0.69215 -0.2921)
			(stroke
				(width 0.1524)
				(type default)
			)
			(layer "B.SilkS")
		)
		(fp_line
			(start -0.69215 0.2921)
			(end 0.69215 0.2921)
			(stroke
				(width 0.1524)
				(type default)
			)
			(layer "B.SilkS")
		)
		(fp_line
			(start 0.51435 -0.2794)
			(end -0.51435 -0.2794)
			(stroke
				(width 0.1)
				(type default)
			)
			(layer "B.Fab")
		)
		(fp_line
			(start -0.51435 -0.2794)
			(end -0.51435 0.2794)
			(stroke
				(width 0.1)
				(type default)
			)
			(layer "B.Fab")
		)
		(fp_line
			(start 0.51435 0.2794)
			(end 0.51435 -0.2794)
			(stroke
				(width 0.1)
				(type default)
			)
			(layer "B.Fab")
		)
		(fp_line
			(start -0.51435 0.2794)
			(end 0.51435 0.2794)
			(stroke
				(width 0.1)
				(type default)
			)
			(layer "B.Fab")
		)
		(pad "1" smd circle
			(at 0.40005 0 270)
			(size 0 0)
			(layers "B.Cu" "B.Mask" "B.Paste")
			(net "P3V3_FPGA_VCCIO1")
		)
		(pad "2" smd circle
			(at -0.40005 0 270)
			(size 0 0)
			(layers "B.Cu" "B.Mask" "B.Paste")
			(net "GND")
		)
		(zone
			(layer "B.Cu")
			(hatch none 0.5)
			(connect_pads
				(clearance 0)
			)
			(min_thickness 0.25)
			(keepout
				(tracks not_allowed)
				(vias allowed)
				(pads allowed)
				(copperpour not_allowed)
				(footprints allowed)
			)
			(placement
				(enabled no)
				(sheetname "")
			)
			(fill
				(thermal_gap 0.5)
				(thermal_bridge_width 0.5)
				(island_removal_mode 0)
			)
			(polygon
				(pts
					(xy 345.381072 -220.57741) (xy 345.439238 -220.48597) (xy 345.439238 -220.28658) (xy 345.381072 -220.19641)
					(xy 345.205812 -220.19641) (xy 345.147392 -220.28658) (xy 345.147392 -220.48597) (xy 345.205558 -220.57741)
				)
			)
		)
	)
	(footprint ""
		(layer "B.Cu")
		(at 290.370006 -305.399948 -90)
		(property "Reference" "C3330"
			(at 0 0 90)
			(layer "B.SilkS")
			(hide yes)
			(effects
				(font
					(size 1.27 1.27)
				)
				(justify mirror)
			)
		)
		(property "Value" ""
			(at 0 0 90)
			(layer "B.Fab")
			(effects
				(font
					(size 1.27 1.27)
				)
				(justify mirror)
			)
		)
		(duplicate_pad_numbers_are_jumpers no)
		(fp_line
			(start -0.299974 0.150114)
			(end 0.299974 0.150114)
			(stroke
				(width 0.1)
				(type default)
			)
			(layer "B.Fab")
		)
		(fp_line
			(start 0.299974 0.150114)
			(end 0.299974 -0.150114)
			(stroke
				(width 0.1)
				(type default)
			)
			(layer "B.Fab")
		)
		(fp_line
			(start -0.299974 -0.150114)
			(end -0.299974 0.150114)
			(stroke
				(width 0.1)
				(type default)
			)
			(layer "B.Fab")
		)
		(fp_line
			(start 0.299974 -0.150114)
			(end -0.299974 -0.150114)
			(stroke
				(width 0.1)
				(type default)
			)
			(layer "B.Fab")
		)
		(pad "1" smd rect
			(at 0.2667 0 90)
			(size 0.3048 0.381)
			(layers "B.Cu" "B.Mask" "B.Paste")
			(net "P1V25_SERDES_VDDPLL_PEX2")
		)
		(pad "2" smd rect
			(at -0.2667 0 90)
			(size 0.3048 0.381)
			(layers "B.Cu" "B.Mask" "B.Paste")
			(net "GND")
		)
	)
	(footprint ""
		(layer "B.Cu")
		(at 419.349936 -296.37482 180)
		(property "Reference" "C3459"
			(at 0 0 0)
			(layer "B.SilkS")
			(hide yes)
			(effects
				(font
					(size 1.27 1.27)
				)
				(justify mirror)
			)
		)
		(property "Value" ""
			(at 0 0 0)
			(layer "B.Fab")
			(effects
				(font
					(size 1.27 1.27)
				)
				(justify mirror)
			)
		)
		(duplicate_pad_numbers_are_jumpers no)
		(fp_line
			(start 0.299974 0.150114)
			(end 0.299974 -0.150114)
			(stroke
				(width 0.1)
				(type default)
			)
			(layer "B.Fab")
		)
		(fp_line
			(start 0.299974 -0.150114)
			(end -0.299974 -0.150114)
			(stroke
				(width 0.1)
				(type default)
			)
			(layer "B.Fab")
		)
		(fp_line
			(start -0.299974 0.150114)
			(end 0.299974 0.150114)
			(stroke
				(width 0.1)
				(type default)
			)
			(layer "B.Fab")
		)
		(fp_line
			(start -0.299974 -0.150114)
			(end -0.299974 0.150114)
			(stroke
				(width 0.1)
				(type default)
			)
			(layer "B.Fab")
		)
		(pad "1" smd rect
			(at 0.2667 0)
			(size 0.3048 0.381)
			(layers "B.Cu" "B.Mask" "B.Paste")
			(net "P1V25_PEX3")
		)
		(pad "2" smd rect
			(at -0.2667 0)
			(size 0.3048 0.381)
			(layers "B.Cu" "B.Mask" "B.Paste")
			(net "GND")
		)
	)
	(footprint ""
		(layer "B.Cu")
		(at 193.641726 -101.069648 180)
		(property "Reference" "R178"
			(at 0 0 0)
			(layer "B.SilkS")
			(hide yes)
			(effects
				(font
					(size 1.27 1.27)
				)
				(justify mirror)
			)
		)
		(property "Value" ""
			(at 0 0 0)
			(layer "B.Fab")
			(effects
				(font
					(size 1.27 1.27)
				)
				(justify mirror)
			)
		)
		(duplicate_pad_numbers_are_jumpers no)
		(fp_line
			(start 0.7874 0.4064)
			(end 0.7874 -0.4064)
			(stroke
				(width 0.1524)
				(type default)
			)
			(layer "B.SilkS")
		)
		(fp_line
			(start 0.7874 -0.4064)
			(end -0.7874 -0.4064)
			(stroke
				(width 0.1524)
				(type default)
			)
			(layer "B.SilkS")
		)
		(fp_line
			(start -0.7874 0.4064)
			(end 0.7874 0.4064)
			(stroke
				(width 0.1524)
				(type default)
			)
			(layer "B.SilkS")
		)
		(fp_line
			(start -0.7874 -0.4064)
			(end -0.7874 0.4064)
			(stroke
				(width 0.1524)
				(type default)
			)
			(layer "B.SilkS")
		)
		(fp_line
			(start 0.67945 0.3048)
			(end 0.67945 -0.305054)
			(stroke
				(width 0.1)
				(type default)
			)
			(layer "B.Fab")
		)
		(fp_line
			(start 0.67945 -0.305054)
			(end 0.12065 -0.305054)
			(stroke
				(width 0.1)
				(type default)
			)
			(layer "B.Fab")
		)
		(fp_line
			(start 0.12065 0.3048)
			(end 0.67945 0.3048)
			(stroke
				(width 0.1)
				(type default)
			)
			(layer "B.Fab")
		)
		(fp_line
			(start 0.12065 0.2794)
			(end 0.12065 0.3048)
			(stroke
				(width 0.1)
				(type default)
			)
			(layer "B.Fab")
		)
		(fp_line
			(start 0.12065 -0.2794)
			(end -0.12065 -0.2794)
			(stroke
				(width 0.1)
				(type default)
			)
			(layer "B.Fab")
		)
		(fp_line
			(start 0.12065 -0.305054)
			(end 0.12065 -0.2794)
			(stroke
				(width 0.1)
				(type default)
			)
			(layer "B.Fab")
		)
		(fp_line
			(start -0.120396 0.3048)
			(end -0.120396 0.2794)
			(stroke
				(width 0.1)
				(type default)
			)
			(layer "B.Fab")
		)
		(fp_line
			(start -0.120396 0.2794)
			(end 0.12065 0.2794)
			(stroke
				(width 0.1)
				(type default)
			)
			(layer "B.Fab")
		)
		(fp_line
			(start -0.12065 -0.2794)
			(end -0.12065 -0.3048)
			(stroke
				(width 0.1)
				(type default)
			)
			(layer "B.Fab")
		)
		(fp_line
			(start -0.12065 -0.3048)
			(end -0.67945 -0.3048)
			(stroke
				(width 0.1)
				(type default)
			)
			(layer "B.Fab")
		)
		(fp_line
			(start -0.67945 0.3048)
			(end -0.120396 0.3048)
			(stroke
				(width 0.1)
				(type default)
			)
			(layer "B.Fab")
		)
		(fp_line
			(start -0.67945 -0.3048)
			(end -0.67945 0.3048)
			(stroke
				(width 0.1)
				(type default)
			)
			(layer "B.Fab")
		)
		(pad "1" smd circle
			(at 0.40005 0)
			(size 0 0)
			(layers "B.Cu" "B.Mask" "B.Paste")
			(net "NIC3_SLOT_ID0")
		)
		(pad "2" smd circle
			(at -0.40005 0)
			(size 0 0)
			(layers "B.Cu" "B.Mask" "B.Paste")
			(net "P3V3_NIC3")
		)
	)
)
